(kicad_pcb
	(version 20260206)
	(generator "pcbnew")
	(generator_version "10.0")
	(general
		(thickness 1.6)
		(legacy_teardrops no)
	)
	(paper "A4")
	(title_block
		(title "Bryce Canyon_R.DPB_16317-1_OCP.brd")
		(comment 1 "Bryce Canyon / footprints 94-97 of 2099")
	)
	(layers
		(0 "F.Cu" signal "TOP")
		(4 "In1.Cu" signal "L2GND")
		(6 "In2.Cu" signal "L3")
		(8 "In3.Cu" signal "L4VCC")
		(10 "In4.Cu" signal "L5VCC")
		(12 "In5.Cu" signal "L6")
		(14 "In6.Cu" signal "L7GND")
		(2 "B.Cu" signal "BOTTOM")
		(9 "F.Adhes" user "F.Adhesive")
		(11 "B.Adhes" user "B.Adhesive")
		(13 "F.Paste" user "Package Geometry/Pastemask Top")
		(15 "B.Paste" user "Package Geometry/Pastemask Bottom")
		(5 "F.SilkS" user "Ref Des/Silkscreen Top")
		(7 "B.SilkS" user "Ref Des/Silkscreen Bottom")
		(1 "F.Mask" user "Board Geometry/Soldermask Top")
		(3 "B.Mask" user "Board Geometry/Soldermask Bottom")
		(17 "Dwgs.User" user "User.Drawings")
		(19 "Cmts.User" user "User.Comments")
		(21 "Eco1.User" user "User.Eco1")
		(23 "Eco2.User" user "User.Eco2")
		(25 "Edge.Cuts" user "Board Geometry/Outline")
		(27 "Margin" user)
		(31 "F.CrtYd" user "Package Geometry/Place Bound Top")
		(29 "B.CrtYd" user "Package Geometry/Place Bound Bottom")
		(35 "F.Fab" user "Ref Des/Assembly Top")
		(33 "B.Fab" user "Ref Des/Assembly Bottom")
	)
	(footprint ""
		(layer "F.Cu")
		(at 265.0617 -380.216156 90)
		(property "Reference" "R1070"
			(at 0 0 90)
			(layer "F.SilkS")
			(hide yes)
			(effects
				(font
					(size 1.27 1.27)
				)
			)
		)
		(property "Value" "0R2J-2-GP"
			(at 0.064008 -3.993896 90)
			(unlocked yes)
			(layer "F.Fab")
			(hide yes)
			(effects
				(font
					(size 1.016 1.016)
					(thickness 0.1524)
				)
			)
		)
		(property "Device Type" "R402H16"
			(at 0.064008 -5.517896 90)
			(unlocked yes)
			(layer "F.Fab")
			(hide yes)
			(effects
				(font
					(size 1.016 1.016)
					(thickness 0.1524)
				)
			)
		)
		(duplicate_pad_numbers_are_jumpers no)
		(fp_line
			(start 0.508 -0.9398)
			(end -0.508 -0.9398)
			(stroke
				(width 0.1524)
				(type default)
			)
			(layer "F.SilkS")
		)
		(fp_line
			(start -0.508 -0.9398)
			(end -0.508 0.9398)
			(stroke
				(width 0.1524)
				(type default)
			)
			(layer "F.SilkS")
		)
		(fp_rect
			(start -0.508 0.9398)
			(end 0.508 -0.9398)
			(stroke
				(width 0)
				(type default)
			)
			(fill no)
			(layer "F.CrtYd")
		)
		(fp_rect
			(start -0.508 0.9398)
			(end 0.508 -0.9398)
			(stroke
				(width 0)
				(type default)
			)
			(fill no)
			(layer "F.Fab")
		)
		(pad "1" smd custom
			(at 0 -0.4445 90)
			(size 0.1397 0.1397)
			(layers "F.Cu" "F.Mask" "F.Paste")
			(net "DRAWER_OUT_NET")
			(options
				(clearance outline)
				(anchor circle)
			)
			(primitives
				(gr_poly
					(pts
						(arc
							(start -0.1778 -0.2794)
							(mid -0.249642 -0.249642)
							(end -0.2794 -0.1778)
						)
						(arc
							(start -0.2794 0.1778)
							(mid -0.249642 0.249642)
							(end -0.1778 0.2794)
						)
						(arc
							(start 0.1778 0.2794)
							(mid 0.249642 0.249642)
							(end 0.2794 0.1778)
						)
						(arc
							(start 0.2794 -0.1778)
							(mid 0.249642 -0.249642)
							(end 0.1778 -0.2794)
						)
					)
					(width 0)
					(fill yes)
				)
			)
		)
		(pad "2" smd custom
			(at 0 0.4445 90)
			(size 0.1397 0.1397)
			(layers "F.Cu" "F.Mask" "F.Paste")
			(net "DRAWER_MOSFET_G")
			(options
				(clearance outline)
				(anchor circle)
			)
			(primitives
				(gr_poly
					(pts
						(arc
							(start -0.1778 -0.2794)
							(mid -0.249642 -0.249642)
							(end -0.2794 -0.1778)
						)
						(arc
							(start -0.2794 0.1778)
							(mid -0.249642 0.249642)
							(end -0.1778 0.2794)
						)
						(arc
							(start 0.1778 0.2794)
							(mid 0.249642 0.249642)
							(end 0.2794 0.1778)
						)
						(arc
							(start 0.2794 -0.1778)
							(mid 0.249642 -0.249642)
							(end 0.1778 -0.2794)
						)
					)
					(width 0)
					(fill yes)
				)
			)
		)
	)
	(footprint ""
		(layer "F.Cu")
		(at 59.749944 -258.910074 -90)
		(property "Reference" "HDDSAS1"
			(at 0 0 270)
			(layer "F.SilkS")
			(hide yes)
			(effects
				(font
					(size 1.27 1.27)
				)
			)
		)
		(property "Value" "SKT-SAS15P-14P-45-GP"
			(at -20.7645 -8.9789 270)
			(unlocked yes)
			(layer "F.Fab")
			(hide yes)
			(effects
				(font
					(size 1.016 1.016)
					(thickness 0.1524)
				)
			)
		)
		(property "Device Type" "10120818-001C-TRLF"
			(at -20.7645 -10.5029 270)
			(unlocked yes)
			(layer "F.Fab")
			(hide yes)
			(effects
				(font
					(size 1.016 1.016)
					(thickness 0.1524)
				)
			)
		)
		(duplicate_pad_numbers_are_jumpers no)
		(fp_line
			(start 1.651 4.2926)
			(end 1.651 3.0099)
			(stroke
				(width 0.1524)
				(type default)
			)
			(layer "F.SilkS")
		)
		(fp_line
			(start 8.509 4.2926)
			(end 1.651 4.2926)
			(stroke
				(width 0.1524)
				(type default)
			)
			(layer "F.SilkS")
		)
		(fp_line
			(start -23.4188 3.0099)
			(end -23.4188 -3.2512)
			(stroke
				(width 0.1524)
				(type default)
			)
			(layer "F.SilkS")
		)
		(fp_line
			(start 1.651 3.0099)
			(end -23.4188 3.0099)
			(stroke
				(width 0.1524)
				(type default)
			)
			(layer "F.SilkS")
		)
		(fp_line
			(start 8.509 3.0099)
			(end 8.509 4.2926)
			(stroke
				(width 0.1524)
				(type default)
			)
			(layer "F.SilkS")
		)
		(fp_line
			(start 23.4188 3.0099)
			(end 8.509 3.0099)
			(stroke
				(width 0.1524)
				(type default)
			)
			(layer "F.SilkS")
		)
		(fp_line
			(start -23.4188 -3.2512)
			(end 23.4188 -3.2512)
			(stroke
				(width 0.1524)
				(type default)
			)
			(layer "F.SilkS")
		)
		(fp_line
			(start 23.4188 -3.2512)
			(end 23.4188 3.0099)
			(stroke
				(width 0.1524)
				(type default)
			)
			(layer "F.SilkS")
		)
		(fp_line
			(start 15.5067 -3.3401)
			(end 16.2687 -3.3401)
			(stroke
				(width 0.3302)
				(type default)
			)
			(layer "F.SilkS")
		)
		(fp_poly
			(pts
				(xy 15.868904 -3.230372) (xy 16.503904 -3.865372) (xy 15.233904 -3.865372)
			)
			(stroke
				(width 0)
				(type default)
			)
			(fill yes)
			(layer "F.SilkS")
		)
		(fp_poly
			(pts
				(xy -22.8727 -2.7559) (xy 22.8727 -2.7559) (xy 22.8727 2.7559) (xy 8.255 2.7559) (xy 8.255 3.5179)
				(xy 1.905 3.5179) (xy 1.905 2.7559) (xy -22.8727 2.7559)
			)
			(stroke
				(width 0)
				(type default)
			)
			(fill no)
			(layer "F.CrtYd")
		)
		(fp_poly
			(pts
				(xy 1.397 4.5466) (xy 1.397 3.2639) (xy -23.6728 3.2639) (xy -23.6728 -3.5052) (xy 23.6728 -3.5052)
				(xy 23.6728 -0.00635) (xy 22.8727 -0.00635) (xy 22.8727 -2.7559) (xy -22.8727 -2.7559) (xy -22.8727 2.7559)
				(xy 1.905 2.7559) (xy 1.905 3.5179) (xy 8.255 3.5179) (xy 8.255 2.7559) (xy 22.8727 2.7559) (xy 22.8727 0.00635)
				(xy 23.6728 0.00635) (xy 23.6728 3.2639) (xy 8.763 3.2639) (xy 8.763 4.5466)
			)
			(stroke
				(width 0)
				(type default)
			)
			(fill no)
			(layer "F.CrtYd")
		)
		(fp_poly
			(pts
				(xy 1.397 4.5466) (xy 1.397 3.2639) (xy -23.6728 3.2639) (xy -23.6728 -3.5052) (xy 23.6728 -3.5052)
				(xy 23.6728 3.2639) (xy 8.763 3.2639) (xy 8.763 4.5466)
			)
			(stroke
				(width 0)
				(type default)
			)
			(fill no)
			(layer "F.Fab")
		)
		(pad "" np_thru_hole circle
			(at -18.874994 0 270)
			(size 0.254 0.254)
			(drill 1.3462)
			(layers "*.Cu" "*.Mask")
			(clearance 0.9017)
			(thermal_gap 0.9017)
		)
		(pad "" np_thru_hole circle
			(at 18.874994 0 270)
			(size 0.254 0.254)
			(drill 0.9398)
			(layers "*.Cu" "*.Mask")
			(clearance 0.6985)
			(thermal_gap 0.6985)
		)
		(pad "G1" smd rect
			(at 21.874988 0 270)
			(size 2.5908 2.5908)
			(layers "F.Cu" "F.Mask" "F.Paste")
			(net "GND")
		)
		(pad "G2" smd rect
			(at -21.874988 0 270)
			(size 2.5908 2.5908)
			(layers "F.Cu" "F.Mask" "F.Paste")
			(net "GND")
		)
		(pad "P1" smd rect
			(at 1.905 -1.82499 270)
			(size 0.6096 2.3622)
			(layers "F.Cu" "F.Mask" "F.Paste")
			(net "Net_1709")
		)
		(pad "P2" smd rect
			(at 0.635 -1.82499 270)
			(size 0.6096 2.3622)
			(layers "F.Cu" "F.Mask" "F.Paste")
			(net "Net_1710")
		)
		(pad "P3" smd rect
			(at -0.635 -1.82499 270)
			(size 0.6096 2.3622)
			(layers "F.Cu" "F.Mask" "F.Paste")
			(net "Net_1711")
		)
		(pad "P4" smd rect
			(at -1.905 -1.82499 270)
			(size 0.6096 2.3622)
			(layers "F.Cu" "F.Mask" "F.Paste")
			(net "GND")
		)
		(pad "P5" smd rect
			(at -3.175 -1.82499 270)
			(size 0.6096 2.3622)
			(layers "F.Cu" "F.Mask" "F.Paste")
			(net "HDD_PRSNT_1")
		)
		(pad "P6" smd rect
			(at -4.445 -1.82499 270)
			(size 0.6096 2.3622)
			(layers "F.Cu" "F.Mask" "F.Paste")
			(net "GND")
		)
		(pad "P7" smd rect
			(at -5.715 -1.82499 270)
			(size 0.6096 2.3622)
			(layers "F.Cu" "F.Mask" "F.Paste")
			(net "5V_PRE_1")
		)
		(pad "P8" smd rect
			(at -6.985 -1.82499 270)
			(size 0.6096 2.3622)
			(layers "F.Cu" "F.Mask" "F.Paste")
			(net "P5V_HDD1")
		)
		(pad "P9" smd rect
			(at -8.255 -1.82499 270)
			(size 0.6096 2.3622)
			(layers "F.Cu" "F.Mask" "F.Paste")
			(net "P5V_HDD1")
		)
		(pad "P10" smd rect
			(at -9.525 -1.82499 270)
			(size 0.6096 2.3622)
			(layers "F.Cu" "F.Mask" "F.Paste")
			(net "GND")
		)
		(pad "P11" smd rect
			(at -10.795 -1.82499 270)
			(size 0.6096 2.3622)
			(layers "F.Cu" "F.Mask" "F.Paste")
			(net "ACT_HDD_1")
		)
		(pad "P12" smd rect
			(at -12.065 -1.82499 270)
			(size 0.6096 2.3622)
			(layers "F.Cu" "F.Mask" "F.Paste")
			(net "GND")
		)
		(pad "P13" smd rect
			(at -13.335 -1.82499 270)
			(size 0.6096 2.3622)
			(layers "F.Cu" "F.Mask" "F.Paste")
			(net "12V_PRE_1")
		)
		(pad "P14" smd rect
			(at -14.605 -1.82499 270)
			(size 0.6096 2.3622)
			(layers "F.Cu" "F.Mask" "F.Paste")
			(net "P12V_HDD1")
		)
		(pad "P15" smd rect
			(at -15.875 -1.82499 270)
			(size 0.6096 2.3622)
			(layers "F.Cu" "F.Mask" "F.Paste")
			(net "P12V_HDD1")
		)
		(pad "S1" smd rect
			(at 15.875 -1.82499 270)
			(size 0.6096 2.3622)
			(layers "F.Cu" "F.Mask" "F.Paste")
			(net "GND")
		)
		(pad "S2" smd rect
			(at 14.605 -1.82499 270)
			(size 0.6096 2.3622)
			(layers "F.Cu" "F.Mask" "F.Paste")
			(net "SAS_HDD_RX_P1")
		)
		(pad "S3" smd rect
			(at 13.335 -1.82499 270)
			(size 0.6096 2.3622)
			(layers "F.Cu" "F.Mask" "F.Paste")
			(net "SAS_HDD_RX_N1")
		)
		(pad "S4" smd rect
			(at 12.065 -1.82499 270)
			(size 0.6096 2.3622)
			(layers "F.Cu" "F.Mask" "F.Paste")
			(net "GND")
		)
		(pad "S5" smd rect
			(at 10.795 -1.82499 270)
			(size 0.6096 2.3622)
			(layers "F.Cu" "F.Mask" "F.Paste")
			(net "PHY_DRV_B_TO_SCC_B_1_DN")
		)
		(pad "S6" smd rect
			(at 9.525 -1.82499 270)
			(size 0.6096 2.3622)
			(layers "F.Cu" "F.Mask" "F.Paste")
			(net "PHY_DRV_B_TO_SCC_B_1_DP")
		)
		(pad "S7" smd rect
			(at 8.255 -1.82499 270)
			(size 0.6096 2.3622)
			(layers "F.Cu" "F.Mask" "F.Paste")
			(net "GND")
		)
		(pad "S8" smd rect
			(at 7.480046 2.845054 270)
			(size 0.508 2.3622)
			(layers "F.Cu" "F.Mask" "F.Paste")
			(net "GND")
		)
		(pad "S9" smd rect
			(at 6.679946 2.845054 270)
			(size 0.508 2.3622)
			(layers "F.Cu" "F.Mask" "F.Paste")
			(net "Net_442")
		)
		(pad "S10" smd rect
			(at 5.8801 2.845054 270)
			(size 0.508 2.3622)
			(layers "F.Cu" "F.Mask" "F.Paste")
			(net "Net_334")
		)
		(pad "S11" smd rect
			(at 5.08 2.845054 270)
			(size 0.508 2.3622)
			(layers "F.Cu" "F.Mask" "F.Paste")
			(net "GND")
		)
		(pad "S12" smd rect
			(at 4.2799 2.845054 270)
			(size 0.508 2.3622)
			(layers "F.Cu" "F.Mask" "F.Paste")
			(net "Net_370")
		)
		(pad "S13" smd rect
			(at 3.480054 2.845054 270)
			(size 0.508 2.3622)
			(layers "F.Cu" "F.Mask" "F.Paste")
			(net "Net_406")
		)
		(pad "S14" smd rect
			(at 2.679954 2.845054 270)
			(size 0.508 2.3622)
			(layers "F.Cu" "F.Mask" "F.Paste")
			(net "GND")
		)
		(zone
			(layer "F.Cu")
			(hatch none 0.5)
			(connect_pads
				(clearance 0)
			)
			(min_thickness 0.25)
			(keepout
				(tracks not_allowed)
				(vias allowed)
				(pads allowed)
				(copperpour not_allowed)
				(footprints allowed)
			)
			(placement
				(enabled no)
				(sheetname "")
			)
			(fill
				(thermal_gap 0.5)
				(thermal_bridge_width 0.5)
				(island_removal_mode 0)
			)
			(polygon
				(pts
					(xy 63.407544 -275.648674) (xy 56.333644 -275.648674) (xy 56.333644 -282.582874) (xy 57.438544 -282.582874)
					(xy 57.438544 -278.468074) (xy 62.061344 -278.468074) (xy 62.061344 -282.582874) (xy 63.407544 -282.582874)
				)
			)
		)
		(zone
			(layer "F.Cu")
			(hatch none 0.5)
			(connect_pads
				(clearance 0)
			)
			(min_thickness 0.25)
			(keepout
				(tracks allowed)
				(vias not_allowed)
				(pads allowed)
				(copperpour not_allowed)
				(footprints allowed)
			)
			(placement
				(enabled no)
				(sheetname "")
			)
			(fill
				(thermal_gap 0.5)
				(thermal_bridge_width 0.5)
				(island_removal_mode 0)
			)
			(polygon
				(pts
					(xy 63.407544 -275.648674) (xy 56.333644 -275.648674) (xy 56.333644 -282.582874) (xy 57.438544 -282.582874)
					(xy 57.438544 -278.468074) (xy 62.061344 -278.468074) (xy 62.061344 -282.582874) (xy 63.407544 -282.582874)
				)
			)
		)
		(zone
			(layer "F.Cu")
			(hatch none 0.5)
			(connect_pads
				(clearance 0)
			)
			(min_thickness 0.25)
			(keepout
				(tracks allowed)
				(vias not_allowed)
				(pads allowed)
				(copperpour not_allowed)
				(footprints allowed)
			)
			(placement
				(enabled no)
				(sheetname "")
			)
			(fill
				(thermal_gap 0.5)
				(thermal_bridge_width 0.5)
				(island_removal_mode 0)
			)
			(polygon
				(pts
					(xy 63.407544 -242.171474) (xy 56.333644 -242.171474) (xy 56.333644 -235.237274) (xy 57.438544 -235.237274)
					(xy 57.438544 -239.352074) (xy 62.061344 -239.352074) (xy 62.061344 -235.237274) (xy 63.407544 -235.237274)
				)
			)
		)
		(zone
			(layer "F.Cu")
			(hatch none 0.5)
			(connect_pads
				(clearance 0)
			)
			(min_thickness 0.25)
			(keepout
				(tracks not_allowed)
				(vias allowed)
				(pads allowed)
				(copperpour not_allowed)
				(footprints allowed)
			)
			(placement
				(enabled no)
				(sheetname "")
			)
			(fill
				(thermal_gap 0.5)
				(thermal_bridge_width 0.5)
				(island_removal_mode 0)
			)
			(polygon
				(pts
					(xy 63.407544 -242.171474) (xy 56.333644 -242.171474) (xy 56.333644 -235.237274) (xy 57.438544 -235.237274)
					(xy 57.438544 -239.352074) (xy 62.061344 -239.352074) (xy 62.061344 -235.237274) (xy 63.407544 -235.237274)
				)
			)
		)
		(zone
			(layers "F.Cu" "B.Cu" "In1.Cu" "In2.Cu" "In3.Cu" "In4.Cu" "In5.Cu" "In6.Cu")
			(hatch none 0.5)
			(connect_pads
				(clearance 0)
			)
			(min_thickness 0.25)
			(keepout
				(tracks not_allowed)
				(vias allowed)
				(pads allowed)
				(copperpour not_allowed)
				(footprints allowed)
			)
			(placement
				(enabled no)
				(sheetname "")
			)
			(fill
				(thermal_gap 0.5)
				(thermal_bridge_width 0.5)
				(island_removal_mode 0)
			)
			(polygon
				(pts
					(arc
						(start 60.524644 -240.03508)
						(mid 58.975244 -240.03508)
						(end 60.524644 -240.03508)
					)
				)
			)
		)
		(zone
			(layers "F.Cu" "B.Cu" "In1.Cu" "In2.Cu" "In3.Cu" "In4.Cu" "In5.Cu" "In6.Cu")
			(hatch none 0.5)
			(connect_pads
				(clearance 0)
			)
			(min_thickness 0.25)
			(keepout
				(tracks not_allowed)
				(vias allowed)
				(pads allowed)
				(copperpour not_allowed)
				(footprints allowed)
			)
			(placement
				(enabled no)
				(sheetname "")
			)
			(fill
				(thermal_gap 0.5)
				(thermal_bridge_width 0.5)
				(island_removal_mode 0)
			)
			(polygon
				(pts
					(arc
						(start 60.727844 -277.785068)
						(mid 58.772044 -277.785068)
						(end 60.727844 -277.785068)
					)
				)
			)
		)
	)
	(footprint ""
		(layer "F.Cu")
		(at 464.0834 -99.3902)
		(property "Reference" "R459"
			(at 0 0 0)
			(layer "F.SilkS")
			(hide yes)
			(effects
				(font
					(size 1.27 1.27)
				)
			)
		)
		(property "Value" "130R3F-GP"
			(at -0.0254 -2.5146 0)
			(unlocked yes)
			(layer "F.Fab")
			(hide yes)
			(effects
				(font
					(size 1.016 1.016)
					(thickness 0.1524)
				)
			)
		)
		(property "Device Type" "R603H22"
			(at -0.0254 -4.0386 0)
			(unlocked yes)
			(layer "F.Fab")
			(hide yes)
			(effects
				(font
					(size 1.016 1.016)
					(thickness 0.1524)
				)
			)
		)
		(duplicate_pad_numbers_are_jumpers no)
		(fp_line
			(start -0.4826 0)
			(end -0.2032 0)
			(stroke
				(width 0.2032)
				(type default)
			)
			(layer "F.SilkS")
		)
		(fp_line
			(start 0.2032 0)
			(end 0.4826 0)
			(stroke
				(width 0.2032)
				(type default)
			)
			(layer "F.SilkS")
		)
		(fp_rect
			(start -0.5842 1.3335)
			(end 0.5842 -1.3335)
			(stroke
				(width 0)
				(type default)
			)
			(fill no)
			(layer "F.CrtYd")
		)
		(fp_rect
			(start -0.5842 1.3335)
			(end 0.5842 -1.3335)
			(stroke
				(width 0)
				(type default)
			)
			(fill no)
			(layer "F.Fab")
		)
		(pad "1" smd custom
			(at 0 -0.762)
			(size 0.2159 0.2159)
			(layers "F.Cu" "F.Mask" "F.Paste")
			(net "P5V_B_4")
			(options
				(clearance outline)
				(anchor circle)
			)
			(primitives
				(gr_poly
					(pts
						(arc
							(start -0.3302 -0.4318)
							(mid -0.402042 -0.402042)
							(end -0.4318 -0.3302)
						)
						(arc
							(start -0.4318 0.3302)
							(mid -0.402042 0.402042)
							(end -0.3302 0.4318)
						)
						(arc
							(start 0.3302 0.4318)
							(mid 0.402042 0.402042)
							(end 0.4318 0.3302)
						)
						(arc
							(start 0.4318 -0.3302)
							(mid 0.402042 -0.402042)
							(end 0.3302 -0.4318)
						)
					)
					(width 0)
					(fill yes)
				)
			)
		)
		(pad "2" smd custom
			(at 0 0.762)
			(size 0.2159 0.2159)
			(layers "F.Cu" "F.Mask" "F.Paste")
			(net "FLT_HDD23")
			(options
				(clearance outline)
				(anchor circle)
			)
			(primitives
				(gr_poly
					(pts
						(arc
							(start -0.3302 -0.4318)
							(mid -0.402042 -0.402042)
							(end -0.4318 -0.3302)
						)
						(arc
							(start -0.4318 0.3302)
							(mid -0.402042 0.402042)
							(end -0.3302 0.4318)
						)
						(arc
							(start 0.3302 0.4318)
							(mid 0.402042 0.402042)
							(end 0.4318 0.3302)
						)
						(arc
							(start 0.4318 -0.3302)
							(mid 0.402042 -0.402042)
							(end 0.3302 -0.4318)
						)
					)
					(width 0)
					(fill yes)
				)
			)
		)
	)
	(footprint ""
		(layer "F.Cu")
		(at 428.2694 -155.575 -90)
		(property "Reference" "R554"
			(at 0 0 270)
			(layer "F.SilkS")
			(hide yes)
			(effects
				(font
					(size 1.27 1.27)
				)
			)
		)
		(property "Value" "2R6F-GP"
			(at -0.0508 -4.8514 270)
			(unlocked yes)
			(layer "F.Fab")
			(hide yes)
			(effects
				(font
					(size 1.016 1.016)
					(thickness 0.1524)
				)
			)
		)
		(property "Device Type" "R1206H26"
			(at 0 -6.3754 270)
			(unlocked yes)
			(layer "F.Fab")
			(hide yes)
			(effects
				(font
					(size 1.016 1.016)
					(thickness 0.1524)
				)
			)
		)
		(duplicate_pad_numbers_are_jumpers no)
		(fp_line
			(start -1.016 2.2352)
			(end -1.016 -2.2352)
			(stroke
				(width 0.1524)
				(type default)
			)
			(layer "F.SilkS")
		)
		(fp_line
			(start 1.016 2.2352)
			(end -1.016 2.2352)
			(stroke
				(width 0.1524)
				(type default)
			)
			(layer "F.SilkS")
		)
		(fp_line
			(start -1.016 -2.2352)
			(end 1.016 -2.2352)
			(stroke
				(width 0.1524)
				(type default)
			)
			(layer "F.SilkS")
		)
		(fp_line
			(start 1.016 -2.2352)
			(end 1.016 2.2352)
			(stroke
				(width 0.1524)
				(type default)
			)
			(layer "F.SilkS")
		)
		(fp_rect
			(start -1.0922 2.3114)
			(end 1.0922 -2.3114)
			(stroke
				(width 0)
				(type default)
			)
			(fill no)
			(layer "F.CrtYd")
		)
		(fp_poly
			(pts
				(xy -1.0922 -2.3114) (xy 1.0922 -2.3114) (xy 1.0922 2.3114) (xy -1.0922 2.3114)
			)
			(stroke
				(width 0)
				(type default)
			)
			(fill no)
			(layer "F.Fab")
		)
		(pad "1" smd rect
			(at 0 -1.397 270)
			(size 1.651 1.27)
			(layers "F.Cu" "F.Mask" "F.Paste")
			(net "P12V_HDD21")
		)
		(pad "2" smd rect
			(at 0 1.397 270)
			(size 1.651 1.27)
			(layers "F.Cu" "F.Mask" "F.Paste")
			(net "12V_PRE_21")
		)
	)
)
